#ISCELL
  mstr_symbols intel_corp_bpage *
  *
#ISCELL
  mstr_standard offpage *
  page183_i1
#ISCELL
  mstr_symbols p3v3_stby *
  page183_i2
#CELL
  mstr_discrete res *
  page183_i3
